# S9S_MB_2U (Grand Teton) — schematic netlist excerpt (pin names and nets, part order shuffled) for the footprints in the layout excerpt that follows; sources: Cadence DE-HDL packaged netlist, KiCad conversion of 03242023_DA0F0TMBIJ0_F0T_Motherboard_J_brd_V01_OCP.brd

C759  Q_CAP_DIFFBUS  DIFF BUS_0.22UF 6.3V 20% X6S  pkg C0201  page 176 : \1\ = P5E_CPU1_PE2_TX_C_DP<7> ; \2\ = P5E_CPU1_PE2_TX_DP<7>
H93  HOLE  EMPTY  pkg TH  page 311 : \1\ = GND
R1477  Q_RES  1K 1% EMPTY  pkg 0402LF  page 200 : A = P3V3_AUX ; B = FM_PCH_XTAL_INPUT_MODE_MGPIO_TE
PR3952  Q_RES  71.5K 1% EMPTY  pkg 0402LF  page 193 : A = P12V_E1S_0 ; B = P12V_E1S_OV_FB_0

(kicad_pcb
	(version 20260206)
	(generator "pcbnew")
	(generator_version "10.0")
	(general
		(thickness 1.6)
		(legacy_teardrops no)
	)
	(paper "A4")
	(title_block
		(title "03242023_DA0F0TMBIJ0_F0T_Motherboard_J_brd_V01_OCP.brd")
		(comment 1 "Grand Teton / footprints 3762-3765 of 6105")
	)
	(layers
		(0 "F.Cu" signal "TOP")
		(4 "In1.Cu" signal "GND")
		(6 "In2.Cu" signal "IN1")
		(8 "In3.Cu" signal "GND1")
		(10 "In4.Cu" signal "IN2")
		(12 "In5.Cu" signal "GND2")
		(14 "In6.Cu" signal "IN3")
		(16 "In7.Cu" signal "GND3")
		(18 "In8.Cu" signal "VCC")
		(20 "In9.Cu" signal "VCC1")
		(22 "In10.Cu" signal "GND4")
		(24 "In11.Cu" signal "IN4")
		(26 "In12.Cu" signal "GND5")
		(28 "In13.Cu" signal "IN5")
		(30 "In14.Cu" signal "GND6")
		(32 "In15.Cu" signal "IN6")
		(34 "In16.Cu" signal "GND7")
		(2 "B.Cu" signal "BOTTOM")
		(9 "F.Adhes" user "F.Adhesive")
		(11 "B.Adhes" user "B.Adhesive")
		(13 "F.Paste" user "Package Geometry/Pastemask Top")
		(15 "B.Paste" user "Package Geometry/Pastemask Bottom")
		(5 "F.SilkS" user "Ref Des/Silkscreen Top")
		(7 "B.SilkS" user "Ref Des/Silkscreen Bottom")
		(1 "F.Mask" user "Board Geometry/Soldermask Top")
		(3 "B.Mask" user "Board Geometry/Soldermask Bottom")
		(17 "Dwgs.User" user "User.Drawings")
		(19 "Cmts.User" user "User.Comments")
		(21 "Eco1.User" user "User.Eco1")
		(23 "Eco2.User" user "User.Eco2")
		(25 "Edge.Cuts" user "Board Geometry/Outline")
		(27 "Margin" user)
		(31 "F.CrtYd" user "Package Geometry/Place Bound Top")
		(29 "B.CrtYd" user "Package Geometry/Place Bound Bottom")
		(35 "F.Fab" user "Ref Des/Assembly Top")
		(33 "B.Fab" user "Ref Des/Assembly Bottom")
	)
	(footprint ""
		(layer "F.Cu")
		(at 252.961648 -56.193182)
		(property "Reference" "PR3952"
			(at 0 0 0)
			(layer "F.SilkS")
			(hide yes)
			(effects
				(font
					(size 1.27 1.27)
				)
			)
		)
		(property "Value" ""
			(at 0 0 0)
			(layer "F.Fab")
			(effects
				(font
					(size 1.27 1.27)
				)
			)
		)
		(duplicate_pad_numbers_are_jumpers no)
		(fp_line
			(start -0.7874 -0.4064)
			(end 0.7874 -0.4064)
			(stroke
				(width 0.1524)
				(type default)
			)
			(layer "F.SilkS")
		)
		(fp_line
			(start -0.7874 0.4064)
			(end -0.7874 -0.4064)
			(stroke
				(width 0.1524)
				(type default)
			)
			(layer "F.SilkS")
		)
		(fp_line
			(start 0.7874 -0.4064)
			(end 0.7874 0.4064)
			(stroke
				(width 0.1524)
				(type default)
			)
			(layer "F.SilkS")
		)
		(fp_line
			(start 0.7874 0.4064)
			(end -0.7874 0.4064)
			(stroke
				(width 0.1524)
				(type default)
			)
			(layer "F.SilkS")
		)
		(fp_line
			(start -0.67945 -0.305054)
			(end -0.12065 -0.305054)
			(stroke
				(width 0.1)
				(type default)
			)
			(layer "F.Fab")
		)
		(fp_line
			(start -0.67945 0.3048)
			(end -0.67945 -0.305054)
			(stroke
				(width 0.1)
				(type default)
			)
			(layer "F.Fab")
		)
		(fp_line
			(start -0.12065 -0.305054)
			(end -0.12065 -0.2794)
			(stroke
				(width 0.1)
				(type default)
			)
			(layer "F.Fab")
		)
		(fp_line
			(start -0.12065 -0.2794)
			(end 0.12065 -0.2794)
			(stroke
				(width 0.1)
				(type default)
			)
			(layer "F.Fab")
		)
		(fp_line
			(start -0.12065 0.2794)
			(end -0.12065 0.3048)
			(stroke
				(width 0.1)
				(type default)
			)
			(layer "F.Fab")
		)
		(fp_line
			(start -0.12065 0.3048)
			(end -0.67945 0.3048)
			(stroke
				(width 0.1)
				(type default)
			)
			(layer "F.Fab")
		)
		(fp_line
			(start 0.120396 0.2794)
			(end -0.12065 0.2794)
			(stroke
				(width 0.1)
				(type default)
			)
			(layer "F.Fab")
		)
		(fp_line
			(start 0.120396 0.3048)
			(end 0.120396 0.2794)
			(stroke
				(width 0.1)
				(type default)
			)
			(layer "F.Fab")
		)
		(fp_line
			(start 0.12065 -0.3048)
			(end 0.67945 -0.3048)
			(stroke
				(width 0.1)
				(type default)
			)
			(layer "F.Fab")
		)
		(fp_line
			(start 0.12065 -0.2794)
			(end 0.12065 -0.3048)
			(stroke
				(width 0.1)
				(type default)
			)
			(layer "F.Fab")
		)
		(fp_line
			(start 0.67945 -0.3048)
			(end 0.67945 0.3048)
			(stroke
				(width 0.1)
				(type default)
			)
			(layer "F.Fab")
		)
		(fp_line
			(start 0.67945 0.3048)
			(end 0.120396 0.3048)
			(stroke
				(width 0.1)
				(type default)
			)
			(layer "F.Fab")
		)
		(pad "1" smd circle
			(at -0.40005 0)
			(size 0 0)
			(layers "F.Cu" "F.Mask" "F.Paste")
			(net "P12V_E1S_0")
		)
		(pad "2" smd circle
			(at 0.40005 0)
			(size 0 0)
			(layers "F.Cu" "F.Mask" "F.Paste")
			(net "P12V_E1S_OV_FB_0")
		)
	)
	(footprint ""
		(layer "F.Cu")
		(at 320.190622 -60.620148)
		(property "Reference" "R1477"
			(at 0 0 0)
			(layer "F.SilkS")
			(hide yes)
			(effects
				(font
					(size 1.27 1.27)
				)
			)
		)
		(property "Value" ""
			(at 0 0 0)
			(layer "F.Fab")
			(effects
				(font
					(size 1.27 1.27)
				)
			)
		)
		(duplicate_pad_numbers_are_jumpers no)
		(fp_line
			(start -0.7874 -0.4064)
			(end 0.7874 -0.4064)
			(stroke
				(width 0.1524)
				(type default)
			)
			(layer "F.SilkS")
		)
		(fp_line
			(start -0.7874 0.4064)
			(end -0.7874 -0.4064)
			(stroke
				(width 0.1524)
				(type default)
			)
			(layer "F.SilkS")
		)
		(fp_line
			(start 0.7874 -0.4064)
			(end 0.7874 0.4064)
			(stroke
				(width 0.1524)
				(type default)
			)
			(layer "F.SilkS")
		)
		(fp_line
			(start 0.7874 0.4064)
			(end -0.7874 0.4064)
			(stroke
				(width 0.1524)
				(type default)
			)
			(layer "F.SilkS")
		)
		(fp_line
			(start -0.67945 -0.305054)
			(end -0.12065 -0.305054)
			(stroke
				(width 0.1)
				(type default)
			)
			(layer "F.Fab")
		)
		(fp_line
			(start -0.67945 0.3048)
			(end -0.67945 -0.305054)
			(stroke
				(width 0.1)
				(type default)
			)
			(layer "F.Fab")
		)
		(fp_line
			(start -0.12065 -0.305054)
			(end -0.12065 -0.2794)
			(stroke
				(width 0.1)
				(type default)
			)
			(layer "F.Fab")
		)
		(fp_line
			(start -0.12065 -0.2794)
			(end 0.12065 -0.2794)
			(stroke
				(width 0.1)
				(type default)
			)
			(layer "F.Fab")
		)
		(fp_line
			(start -0.12065 0.2794)
			(end -0.12065 0.3048)
			(stroke
				(width 0.1)
				(type default)
			)
			(layer "F.Fab")
		)
		(fp_line
			(start -0.12065 0.3048)
			(end -0.67945 0.3048)
			(stroke
				(width 0.1)
				(type default)
			)
			(layer "F.Fab")
		)
		(fp_line
			(start 0.120396 0.2794)
			(end -0.12065 0.2794)
			(stroke
				(width 0.1)
				(type default)
			)
			(layer "F.Fab")
		)
		(fp_line
			(start 0.120396 0.3048)
			(end 0.120396 0.2794)
			(stroke
				(width 0.1)
				(type default)
			)
			(layer "F.Fab")
		)
		(fp_line
			(start 0.12065 -0.3048)
			(end 0.67945 -0.3048)
			(stroke
				(width 0.1)
				(type default)
			)
			(layer "F.Fab")
		)
		(fp_line
			(start 0.12065 -0.2794)
			(end 0.12065 -0.3048)
			(stroke
				(width 0.1)
				(type default)
			)
			(layer "F.Fab")
		)
		(fp_line
			(start 0.67945 -0.3048)
			(end 0.67945 0.3048)
			(stroke
				(width 0.1)
				(type default)
			)
			(layer "F.Fab")
		)
		(fp_line
			(start 0.67945 0.3048)
			(end 0.120396 0.3048)
			(stroke
				(width 0.1)
				(type default)
			)
			(layer "F.Fab")
		)
		(pad "1" smd circle
			(at -0.40005 0)
			(size 0 0)
			(layers "F.Cu" "F.Mask" "F.Paste")
			(net "P3V3_AUX")
		)
		(pad "2" smd circle
			(at 0.40005 0)
			(size 0 0)
			(layers "F.Cu" "F.Mask" "F.Paste")
			(net "FM_PCH_XTAL_INPUT_MODE_MGPIO_TE")
		)
	)
	(footprint ""
		(layer "F.Cu")
		(at 371.29847 -435.600094)
		(property "Reference" "H93"
			(at -6.50113 -4.379976 0)
			(unlocked yes)
			(layer "F.SilkS")
			(effects
				(font
					(size 0.7874 0.5842)
					(thickness 0.1524)
				)
				(justify left)
			)
		)
		(property "Value" ""
			(at 0 0 0)
			(layer "F.Fab")
			(effects
				(font
					(size 1.27 1.27)
				)
			)
		)
		(duplicate_pad_numbers_are_jumpers no)
		(pad "1" thru_hole circle
			(at 0 0)
			(size 10.0076 10.0076)
			(drill 5.6134)
			(layers "*.Cu" "*.Mask")
			(remove_unused_layers no)
			(net "GND")
			(clearance -1.9431)
		)
	)
	(footprint ""
		(layer "F.Cu")
		(at 144.635474 -402.371052 -90)
		(property "Reference" "C759"
			(at 0 0 270)
			(layer "F.SilkS")
			(hide yes)
			(effects
				(font
					(size 1.27 1.27)
				)
			)
		)
		(property "Value" ""
			(at 0 0 270)
			(layer "F.Fab")
			(effects
				(font
					(size 1.27 1.27)
				)
			)
		)
		(duplicate_pad_numbers_are_jumpers no)
		(fp_line
			(start -0.299974 0.150114)
			(end -0.299974 -0.150114)
			(stroke
				(width 0.1)
				(type default)
			)
			(layer "F.Fab")
		)
		(fp_line
			(start 0.299974 0.150114)
			(end -0.299974 0.150114)
			(stroke
				(width 0.1)
				(type default)
			)
			(layer "F.Fab")
		)
		(fp_line
			(start -0.299974 -0.150114)
			(end 0.299974 -0.150114)
			(stroke
				(width 0.1)
				(type default)
			)
			(layer "F.Fab")
		)
		(fp_line
			(start 0.299974 -0.150114)
			(end 0.299974 0.150114)
			(stroke
				(width 0.1)
				(type default)
			)
			(layer "F.Fab")
		)
		(pad "1" smd rect
			(at -0.2667 0 270)
			(size 0.3048 0.381)
			(layers "F.Cu" "F.Mask" "F.Paste")
			(net "P5E_CPU1_PE2_TX_C_DP<7>")
		)
		(pad "2" smd rect
			(at 0.2667 0 270)
			(size 0.3048 0.381)
			(layers "F.Cu" "F.Mask" "F.Paste")
			(net "P5E_CPU1_PE2_TX_DP<7>")
		)
	)
)
